# ECP5 - Datacenter Secure Control Module (DC-SCM) — KiCad project settings (.kicad_pro: net classes, design rules, text variables)
{
  "board": {
    "3dviewports": [],
    "design_settings": {
      "defaults": {
        "board_outline_line_width": 0.049999999999999996,
        "copper_line_width": 0.19999999999999998,
        "copper_text_italic": false,
        "copper_text_size_h": 1.5,
        "copper_text_size_v": 1.5,
        "copper_text_thickness": 0.3,
        "copper_text_upright": false,
        "courtyard_line_width": 0.049999999999999996,
        "dimension_precision": 4,
        "dimension_units": 3,
        "dimensions": {
          "arrow_length": 1270000,
          "extension_offset": 500000,
          "keep_text_aligned": true,
          "suppress_zeroes": false,
          "text_position": 0,
          "units_format": 1
        },
        "fab_line_width": 0.09999999999999999,
        "fab_text_italic": false,
        "fab_text_size_h": 1.0,
        "fab_text_size_v": 1.0,
        "fab_text_thickness": 0.15,
        "fab_text_upright": false,
        "other_line_width": 0.09999999999999999,
        "other_text_italic": false,
        "other_text_size_h": 1.0,
        "other_text_size_v": 1.0,
        "other_text_thickness": 0.15,
        "other_text_upright": false,
        "pads": {
          "drill": 0.0,
          "height": 5.9,
          "width": 5.9
        },
        "silk_line_width": 0.127,
        "silk_text_italic": false,
        "silk_text_size_h": 0.7,
        "silk_text_size_v": 0.7,
        "silk_text_thickness": 0.127,
        "silk_text_upright": false,
        "zones": {
          "45_degree_only": false,
          "min_clearance": 0.15
        }
      },
      "diff_pair_dimensions": [
        {
          "gap": 0.0,
          "via_gap": 0.0,
          "width": 0.0
        }
      ],
      "drc_exclusions": [],
      "meta": {
        "filename": "board_design_settings.json",
        "version": 2
      },
      "rule_severities": {
        "annular_width": "error",
        "clearance": "error",
        "connection_width": "warning",
        "copper_edge_clearance": "error",
        "copper_sliver": "warning",
        "courtyards_overlap": "error",
        "diff_pair_gap_out_of_range": "error",
        "diff_pair_uncoupled_length_too_long": "error",
        "drill_out_of_range": "error",
        "duplicate_footprints": "warning",
        "extra_footprint": "warning",
        "footprint": "error",
        "footprint_type_mismatch": "ignore",
        "hole_clearance": "error",
        "hole_near_hole": "error",
        "invalid_outline": "error",
        "isolated_copper": "warning",
        "item_on_disabled_layer": "error",
        "items_not_allowed": "error",
        "length_out_of_range": "error",
        "lib_footprint_issues": "warning",
        "lib_footprint_mismatch": "warning",
        "malformed_courtyard": "error",
        "microvia_drill_out_of_range": "error",
        "missing_courtyard": "warning",
        "missing_footprint": "warning",
        "net_conflict": "warning",
        "npth_inside_courtyard": "warning",
        "padstack": "error",
        "pth_inside_courtyard": "warning",
        "shorting_items": "error",
        "silk_edge_clearance": "warning",
        "silk_over_copper": "ignore",
        "silk_overlap": "warning",
        "skew_out_of_range": "error",
        "solder_mask_bridge": "error",
        "starved_thermal": "error",
        "text_height": "warning",
        "text_thickness": "warning",
        "through_hole_pad_without_hole": "error",
        "too_many_vias": "error",
        "track_dangling": "warning",
        "track_width": "error",
        "tracks_crossing": "error",
        "unconnected_items": "error",
        "unresolved_variable": "error",
        "via_dangling": "warning",
        "zones_intersect": "error"
      },
      "rule_severitieslegacy_courtyards_overlap": true,
      "rule_severitieslegacy_no_courtyard_defined": false,
      "rules": {
        "allow_blind_buried_vias": true,
        "allow_microvias": false,
        "max_error": 0.005,
        "min_clearance": 0.09999999999999999,
        "min_connection": 0.0,
        "min_copper_edge_clearance": 0.024999999999999998,
        "min_hole_clearance": 0.25,
        "min_hole_to_hole": 0.25,
        "min_microvia_diameter": 0.19999999999999998,
        "min_microvia_drill": 0.09999999999999999,
        "min_resolved_spokes": 2,
        "min_silk_clearance": 0.0,
        "min_text_height": 0.7,
        "min_text_thickness": 0.08,
        "min_through_hole_diameter": 0.19999999999999998,
        "min_track_width": 0.09999999999999999,
        "min_via_annular_width": 0.049999999999999996,
        "min_via_diameter": 0.44999999999999996,
        "solder_mask_to_copper_clearance": 0.0,
        "use_height_for_length_calcs": true
      },
      "teardrop_options": [
        {
          "td_allow_use_two_tracks": true,
          "td_curve_segcount": 5,
          "td_on_pad_in_zone": false,
          "td_onpadsmd": true,
          "td_onroundshapesonly": false,
          "td_ontrackend": false,
          "td_onviapad": true
        }
      ],
      "teardrop_parameters": [
        {
          "td_curve_segcount": 0,
          "td_height_ratio": 1.0,
          "td_length_ratio": 0.5,
          "td_maxheight": 2.0,
          "td_maxlen": 1.0,
          "td_target_name": "td_round_shape",
          "td_width_to_size_filter_ratio": 0.9
        },
        {
          "td_curve_segcount": 0,
          "td_height_ratio": 1.0,
          "td_length_ratio": 0.5,
          "td_maxheight": 2.0,
          "td_maxlen": 1.0,
          "td_target_name": "td_rect_shape",
          "td_width_to_size_filter_ratio": 0.9
        },
        {
          "td_curve_segcount": 0,
          "td_height_ratio": 1.0,
          "td_length_ratio": 0.5,
          "td_maxheight": 2.0,
          "td_maxlen": 1.0,
          "td_target_name": "td_track_end",
          "td_width_to_size_filter_ratio": 0.9
        }
      ],
      "track_widths": [
        0.0,
        0.1,
        0.127,
        0.15,
        0.2,
        0.3,
        0.5
      ],
      "via_dimensions": [
        {
          "diameter": 0.0,
          "drill": 0.0
        }
      ],
      "zones_allow_external_fillets": false,
      "zones_use_no_outline": true
    },
    "layer_presets": [],
    "viewports": []
  },
  "boards": [],
  "cvpcb": {
    "equivalence_files": []
  },
  "erc": {
    "erc_exclusions": [],
    "meta": {
      "version": 0
    },
    "pin_map": [
      [
        0,
        0,
        0,
        0,
        0,
        0,
        1,
        0,
        0,
        0,
        0,
        2
      ],
      [
        0,
        2,
        0,
        1,
        0,
        0,
        1,
        0,
        2,
        2,
        2,
        2
      ],
      [
        0,
        0,
        0,
        0,
        0,
        0,
        1,
        0,
        1,
        0,
        1,
        2
      ],
      [
        0,
        1,
        0,
        0,
        0,
        0,
        1,
        1,
        2,
        1,
        1,
        2
      ],
      [
        0,
        0,
        0,
        0,
        0,
        0,
        1,
        0,
        0,
        0,
        0,
        2
      ],
      [
        0,
        0,
        0,
        0,
        0,
        0,
        0,
        0,
        0,
        0,
        0,
        2
      ],
      [
        1,
        1,
        1,
        1,
        1,
        0,
        1,
        1,
        1,
        1,
        1,
        2
      ],
      [
        0,
        0,
        0,
        1,
        0,
        0,
        1,
        0,
        0,
        0,
        0,
        2
      ],
      [
        0,
        2,
        1,
        2,
        0,
        0,
        1,
        0,
        2,
        2,
        2,
        2
      ],
      [
        0,
        2,
        0,
        1,
        0,
        0,
        1,
        0,
        2,
        0,
        0,
        2
      ],
      [
        0,
        2,
        1,
        1,
        0,
        0,
        1,
        0,
        2,
        0,
        0,
        2
      ],
      [
        2,
        2,
        2,
        2,
        2,
        2,
        2,
        2,
        2,
        2,
        2,
        2
      ]
    ],
    "rule_severities": {
      "bus_definition_conflict": "error",
      "bus_entry_needed": "error",
      "bus_to_bus_conflict": "error",
      "bus_to_net_conflict": "error",
      "conflicting_netclasses": "error",
      "different_unit_footprint": "error",
      "different_unit_net": "error",
      "duplicate_reference": "error",
      "duplicate_sheet_names": "error",
      "endpoint_off_grid": "warning",
      "extra_units": "error",
      "global_label_dangling": "warning",
      "hier_label_mismatch": "error",
      "label_dangling": "error",
      "lib_symbol_issues": "warning",
      "missing_bidi_pin": "warning",
      "missing_input_pin": "warning",
      "missing_power_pin": "error",
      "missing_unit": "warning",
      "multiple_net_names": "warning",
      "net_not_bus_member": "warning",
      "no_connect_connected": "error",
      "no_connect_dangling": "warning",
      "pin_not_connected": "error",
      "pin_not_driven": "error",
      "pin_to_pin": "ignore",
      "power_pin_not_driven": "error",
      "similar_labels": "warning",
      "simulation_model_issue": "ignore",
      "unannotated": "error",
      "unit_value_mismatch": "error",
      "unresolved_variable": "error",
      "wire_dangling": "error"
    }
  },
  "libraries": {
    "pinned_footprint_libs": [],
    "pinned_symbol_libs": []
  },
  "meta": {
    "filename": "ecp5-dc-scm.kicad_pro",
    "version": 1
  },
  "net_settings": {
    "classes": [
      {
        "bus_width": 12,
        "clearance": 0.1,
        "diff_pair_gap": 0.25,
        "diff_pair_via_gap": 0.25,
        "diff_pair_width": 0.2,
        "line_style": 0,
        "microvia_diameter": 0.3,
        "microvia_drill": 0.1,
        "name": "Default",
        "pcb_color": "rgba(0, 0, 0, 0.000)",
        "schematic_color": "rgba(0, 0, 0, 0.000)",
        "track_width": 0.25,
        "via_diameter": 0.5,
        "via_drill": 0.2,
        "wire_width": 6
      },
      {
        "bus_width": 12,
        "clearance": 0.11,
        "diff_pair_gap": 0.11,
        "diff_pair_via_gap": 0.25,
        "diff_pair_width": 0.11,
        "line_style": 0,
        "microvia_diameter": 0.5,
        "microvia_drill": 0.2,
        "name": "Ethernet",
        "pcb_color": "rgba(0, 0, 0, 0.000)",
        "schematic_color": "rgba(0, 0, 0, 0.000)",
        "track_width": 0.11,
        "via_diameter": 0.5,
        "via_drill": 0.2,
        "wire_width": 6
      },
      {
        "bus_width": 12,
        "clearance": 0.1,
        "diff_pair_gap": 0.123,
        "diff_pair_via_gap": 0.25,
        "diff_pair_width": 0.127,
        "line_style": 0,
        "microvia_diameter": 0.5,
        "microvia_drill": 0.1,
        "name": "PCIe",
        "pcb_color": "rgba(0, 0, 0, 0.000)",
        "schematic_color": "rgba(0, 0, 0, 0.000)",
        "track_width": 0.11,
        "via_diameter": 0.5,
        "via_drill": 0.2,
        "wire_width": 6
      },
      {
        "bus_width": 12,
        "clearance": 0.1,
        "diff_pair_gap": 0.15,
        "diff_pair_via_gap": 0.25,
        "diff_pair_width": 0.16,
        "line_style": 0,
        "microvia_diameter": 0.3,
        "microvia_drill": 0.1,
        "name": "ULPI",
        "pcb_color": "rgba(0, 0, 0, 0.000)",
        "schematic_color": "rgba(0, 0, 0, 0.000)",
        "track_width": 0.15,
        "via_diameter": 0.5,
        "via_drill": 0.2,
        "wire_width": 6
      },
      {
        "bus_width": 12,
        "clearance": 0.15,
        "diff_pair_gap": 0.15,
        "diff_pair_via_gap": 0.25,
        "diff_pair_width": 0.16,
        "line_style": 0,
        "microvia_diameter": 0.3,
        "microvia_drill": 0.1,
        "name": "USB",
        "pcb_color": "rgba(0, 0, 0, 0.000)",
        "schematic_color": "rgba(0, 0, 0, 0.000)",
        "track_width": 0.16,
        "via_diameter": 0.5,
        "via_drill": 0.2,
        "wire_width": 6
      }
    ],
    "meta": {
      "version": 3
    },
    "net_colors": null,
    "netclass_assignments": null,
    "netclass_patterns": [
      {
        "netclass": "Ethernet",
        "pattern": "/Ethernet/ETH1_N"
      },
      {
        "netclass": "Ethernet",
        "pattern": "/Ethernet/ETH1_P"
      },
      {
        "netclass": "Ethernet",
        "pattern": "/Ethernet/ETH2_N"
      },
      {
        "netclass": "Ethernet",
        "pattern": "/Ethernet/ETH2_P"
      },
      {
        "netclass": "Ethernet",
        "pattern": "/Ethernet/ETH3_N"
      },
      {
        "netclass": "Ethernet",
        "pattern": "/Ethernet/ETH3_P"
      },
      {
        "netclass": "Ethernet",
        "pattern": "/Ethernet/ETH4_N"
      },
      {
        "netclass": "Ethernet",
        "pattern": "/Ethernet/ETH4_P"
      },
      {
        "netclass": "PCIe",
        "pattern": "/FPGA banks/PCIE_BMC_TX_C_DN"
      },
      {
        "netclass": "PCIe",
        "pattern": "/FPGA banks/PCIE_BMC_TX_C_DP"
      },
      {
        "netclass": "PCIe",
        "pattern": "CLK_100M_PCIE_DN"
      },
      {
        "netclass": "PCIe",
        "pattern": "CLK_100M_PCIE_DP"
      },
      {
        "netclass": "PCIe",
        "pattern": "CLK_PCIE_x4_DN"
      },
      {
        "netclass": "PCIe",
        "pattern": "CLK_PCIE_x4_DP"
      },
      {
        "netclass": "PCIe",
        "pattern": "PCIE_BMC_RX_DN"
      },
      {
        "netclass": "PCIe",
        "pattern": "PCIE_BMC_RX_DP"
      },
      {
        "netclass": "PCIe",
        "pattern": "PCIE_BMC_TX_DN"
      },
      {
        "netclass": "PCIe",
        "pattern": "PCIE_BMC_TX_DP"
      },
      {
        "netclass": "PCIe",
        "pattern": "PCIE_HPM_RX0_N"
      },
      {
        "netclass": "PCIe",
        "pattern": "PCIE_HPM_RX0_P"
      },
      {
        "netclass": "PCIe",
        "pattern": "PCIE_HPM_RX1_N"
      },
      {
        "netclass": "PCIe",
        "pattern": "PCIE_HPM_RX1_P"
      },
      {
        "netclass": "PCIe",
        "pattern": "PCIE_HPM_RX2_N"
      },
      {
        "netclass": "PCIe",
        "pattern": "PCIE_HPM_RX2_P"
      },
      {
        "netclass": "PCIe",
        "pattern": "PCIE_HPM_RX3_N"
      },
      {
        "netclass": "PCIe",
        "pattern": "PCIE_HPM_RX3_P"
      },
      {
        "netclass": "PCIe",
        "pattern": "PCIE_HPM_TX0_N"
      },
      {
        "netclass": "PCIe",
        "pattern": "PCIE_HPM_TX0_P"
      },
      {
        "netclass": "PCIe",
        "pattern": "PCIE_HPM_TX1_N"
      },
      {
        "netclass": "PCIe",
        "pattern": "PCIE_HPM_TX1_P"
      },
      {
        "netclass": "PCIe",
        "pattern": "PCIE_HPM_TX2_N"
      },
      {
        "netclass": "PCIe",
        "pattern": "PCIE_HPM_TX2_P"
      },
      {
        "netclass": "PCIe",
        "pattern": "PCIE_HPM_TX3_N"
      },
      {
        "netclass": "PCIe",
        "pattern": "PCIE_HPM_TX3_P"
      },
      {
        "netclass": "ULPI",
        "pattern": "ULPI1_CLKO"
      },
      {
        "netclass": "ULPI",
        "pattern": "ULPI1_D0"
      },
      {
        "netclass": "ULPI",
        "pattern": "ULPI1_D1"
      },
      {
        "netclass": "ULPI",
        "pattern": "ULPI1_D2"
      },
      {
        "netclass": "ULPI",
        "pattern": "ULPI1_D3"
      },
      {
        "netclass": "ULPI",
        "pattern": "ULPI1_D4"
      },
      {
        "netclass": "ULPI",
        "pattern": "ULPI1_D5"
      },
      {
        "netclass": "ULPI",
        "pattern": "ULPI1_D6"
      },
      {
        "netclass": "ULPI",
        "pattern": "ULPI1_D7"
      },
      {
        "netclass": "ULPI",
        "pattern": "ULPI1_DIR"
      },
      {
        "netclass": "ULPI",
        "pattern": "ULPI1_NXT"
      },
      {
        "netclass": "ULPI",
        "pattern": "ULPI1_RESET"
      },
      {
        "netclass": "ULPI",
        "pattern": "ULPI1_STP"
      },
      {
        "netclass": "ULPI",
        "pattern": "ULPI2_CLKO"
      },
      {
        "netclass": "ULPI",
        "pattern": "ULPI2_D0"
      },
      {
        "netclass": "ULPI",
        "pattern": "ULPI2_D1"
      },
      {
        "netclass": "ULPI",
        "pattern": "ULPI2_D2"
      },
      {
        "netclass": "ULPI",
        "pattern": "ULPI2_D3"
      },
      {
        "netclass": "ULPI",
        "pattern": "ULPI2_D4"
      },
      {
        "netclass": "ULPI",
        "pattern": "ULPI2_D5"
      },
      {
        "netclass": "ULPI",
        "pattern": "ULPI2_D6"
      },
      {
        "netclass": "ULPI",
        "pattern": "ULPI2_D7"
      },
      {
        "netclass": "ULPI",
        "pattern": "ULPI2_NXT"
      },
      {
        "netclass": "ULPI",
        "pattern": "ULPI2_RESET"
      },
      {
        "netclass": "ULPI",
        "pattern": "ULPI2_STP"
      },
      {
        "netclass": "ULPI",
        "pattern": "ULPI_DIR"
      },
      {
        "netclass": "USB",
        "pattern": "USB1_DN"
      },
      {
        "netclass": "USB",
        "pattern": "USB1_DP"
      },
      {
        "netclass": "USB",
        "pattern": "USB2_DN"
      },
      {
        "netclass": "USB",
        "pattern": "USB2_DP"
      }
    ]
  },
  "pcbnew": {
    "last_paths": {
      "gencad": "",
      "idf": "",
      "netlist": "",
      "specctra_dsn": "",
      "step": "",
      "vrml": ""
    },
    "page_layout_descr_file": ""
  },
  "schematic": {
    "annotate_start_num": 0,
    "drawing": {
      "dashed_lines_dash_length_ratio": 12.0,
      "dashed_lines_gap_length_ratio": 3.0,
      "default_line_thickness": 6.0,
      "default_text_size": 50.0,
      "field_names": [],
      "intersheets_ref_own_page": false,
      "intersheets_ref_prefix": "",
      "intersheets_ref_short": false,
      "intersheets_ref_show": false,
      "intersheets_ref_suffix": "",
      "junction_size_choice": 3,
      "label_size_ratio": 0.25,
      "pin_symbol_size": 0.0,
      "text_offset_ratio": 0.08
    },
    "legacy_lib_dir": "",
    "legacy_lib_list": [],
    "meta": {
      "version": 1
    },
    "net_format_name": "",
    "ngspice": {
      "fix_include_paths": true,
      "fix_passive_vals": false,
      "meta": {
        "version": 0
      },
      "model_mode": 0,
      "workbook_filename": ""
    },
    "page_layout_descr_file": "",
    "plot_directory": "./doc",
    "spice_adjust_passive_values": false,
    "spice_current_sheet_as_root": false,
    "spice_external_command": "spice \"%I\"",
    "spice_model_current_sheet_as_root": true,
    "spice_save_all_currents": false,
    "spice_save_all_voltages": false,
    "subpart_first_id": 65,
    "subpart_id_separator": 0
  },
  "sheets": [
    [
      "",
      ""
    ],
    [
      "",
      "Ethernet"
    ],
    [
      "",
      "FPGA power supply"
    ],
    [
      "",
      "PCIe-connector"
    ],
    [
      "",
      "FPGA banks"
    ],
    [
      "",
      "RoT"
    ],
    [
      "",
      "Edge connector"
    ],
    [
      "",
      "Interfaces"
    ],
    [
      "",
      "DDR3"
    ],
    [
      "",
      "Power supply"
    ]
  ],
  "text_variables": {}
}
